G04 #@! TF.GenerationSoftware,KiCad,Pcbnew,(5.0.1)-3*
G04 #@! TF.CreationDate,2019-04-10T15:36:06+02:00*
G04 #@! TF.ProjectId,discovery,646973636F766572792E6B696361645F,rev?*
G04 #@! TF.SameCoordinates,PX4c4640PY8a48028*
G04 #@! TF.FileFunction,Other,Fab,Top*
%FSLAX46Y46*%
G04 Gerber Fmt 4.6, Leading zero omitted, Abs format (unit mm)*
%MOMM*%
%LPD*%
G01*
G04 APERTURE LIST*
%ADD10C,0.125000*%
%ADD11C,0.150000*%
G04 APERTURE END LIST*
G04 #@! TO.C,J2*
D10*
X34445137Y40263055D02*
X34480851Y40227340D01*
X34516565Y40120198D01*
X34516565Y40048769D01*
X34480851Y39941626D01*
X34409422Y39870198D01*
X34337994Y39834483D01*
X34195137Y39798769D01*
X34087994Y39798769D01*
X33945137Y39834483D01*
X33873708Y39870198D01*
X33802280Y39941626D01*
X33766565Y40048769D01*
X33766565Y40120198D01*
X33802280Y40227340D01*
X33837994Y40263055D01*
X34516565Y40691626D02*
X34480851Y40620198D01*
X34445137Y40584483D01*
X34373708Y40548769D01*
X34159422Y40548769D01*
X34087994Y40584483D01*
X34052280Y40620198D01*
X34016565Y40691626D01*
X34016565Y40798769D01*
X34052280Y40870198D01*
X34087994Y40905912D01*
X34159422Y40941626D01*
X34373708Y40941626D01*
X34445137Y40905912D01*
X34480851Y40870198D01*
X34516565Y40798769D01*
X34516565Y40691626D01*
X34016565Y41263055D02*
X34516565Y41263055D01*
X34087994Y41263055D02*
X34052280Y41298769D01*
X34016565Y41370198D01*
X34016565Y41477340D01*
X34052280Y41548769D01*
X34123708Y41584483D01*
X34516565Y41584483D01*
X34016565Y41941626D02*
X34516565Y41941626D01*
X34087994Y41941626D02*
X34052280Y41977340D01*
X34016565Y42048769D01*
X34016565Y42155912D01*
X34052280Y42227340D01*
X34123708Y42263055D01*
X34516565Y42263055D01*
X34587994Y42441626D02*
X34587994Y43013055D01*
X33766565Y43334483D02*
X33766565Y43405912D01*
X33802280Y43477340D01*
X33837994Y43513055D01*
X33909422Y43548769D01*
X34052280Y43584483D01*
X34230851Y43584483D01*
X34373708Y43548769D01*
X34445137Y43513055D01*
X34480851Y43477340D01*
X34516565Y43405912D01*
X34516565Y43334483D01*
X34480851Y43263055D01*
X34445137Y43227340D01*
X34373708Y43191626D01*
X34230851Y43155912D01*
X34052280Y43155912D01*
X33909422Y43191626D01*
X33837994Y43227340D01*
X33802280Y43263055D01*
X33766565Y43334483D01*
X33837994Y43870198D02*
X33802280Y43905912D01*
X33766565Y43977340D01*
X33766565Y44155912D01*
X33802280Y44227340D01*
X33837994Y44263055D01*
X33909422Y44298769D01*
X33980851Y44298769D01*
X34087994Y44263055D01*
X34516565Y43834483D01*
X34516565Y44298769D01*
X34516565Y44548769D02*
X34016565Y44941626D01*
X34016565Y44548769D02*
X34516565Y44941626D01*
X33766565Y45370198D02*
X33766565Y45441626D01*
X33802280Y45513055D01*
X33837994Y45548769D01*
X33909422Y45584483D01*
X34052280Y45620198D01*
X34230851Y45620198D01*
X34373708Y45584483D01*
X34445137Y45548769D01*
X34480851Y45513055D01*
X34516565Y45441626D01*
X34516565Y45370198D01*
X34480851Y45298769D01*
X34445137Y45263055D01*
X34373708Y45227340D01*
X34230851Y45191626D01*
X34052280Y45191626D01*
X33909422Y45227340D01*
X33837994Y45263055D01*
X33802280Y45298769D01*
X33766565Y45370198D01*
X33766565Y45870198D02*
X33766565Y46334483D01*
X34052280Y46084483D01*
X34052280Y46191626D01*
X34087994Y46263055D01*
X34123708Y46298769D01*
X34195137Y46334483D01*
X34373708Y46334483D01*
X34445137Y46298769D01*
X34480851Y46263055D01*
X34516565Y46191626D01*
X34516565Y45977340D01*
X34480851Y45905912D01*
X34445137Y45870198D01*
X34587994Y46477340D02*
X34587994Y47048769D01*
X34516565Y47227340D02*
X33766565Y47227340D01*
X33766565Y47513055D01*
X33802280Y47584483D01*
X33837994Y47620198D01*
X33909422Y47655912D01*
X34016565Y47655912D01*
X34087994Y47620198D01*
X34123708Y47584483D01*
X34159422Y47513055D01*
X34159422Y47227340D01*
X34445137Y48405912D02*
X34480851Y48370198D01*
X34516565Y48263055D01*
X34516565Y48191626D01*
X34480851Y48084483D01*
X34409422Y48013055D01*
X34337994Y47977340D01*
X34195137Y47941626D01*
X34087994Y47941626D01*
X33945137Y47977340D01*
X33873708Y48013055D01*
X33802280Y48084483D01*
X33766565Y48191626D01*
X33766565Y48263055D01*
X33802280Y48370198D01*
X33837994Y48405912D01*
X34516565Y48727340D02*
X33766565Y48727340D01*
X34480851Y49370198D02*
X34516565Y49298769D01*
X34516565Y49155912D01*
X34480851Y49084483D01*
X34409422Y49048769D01*
X34123708Y49048769D01*
X34052280Y49084483D01*
X34016565Y49155912D01*
X34016565Y49298769D01*
X34052280Y49370198D01*
X34123708Y49405912D01*
X34195137Y49405912D01*
X34266565Y49048769D01*
G04 #@! TO.C,J4*
X2093137Y40255255D02*
X2128851Y40219540D01*
X2164565Y40112398D01*
X2164565Y40040969D01*
X2128851Y39933826D01*
X2057422Y39862398D01*
X1985994Y39826683D01*
X1843137Y39790969D01*
X1735994Y39790969D01*
X1593137Y39826683D01*
X1521708Y39862398D01*
X1450280Y39933826D01*
X1414565Y40040969D01*
X1414565Y40112398D01*
X1450280Y40219540D01*
X1485994Y40255255D01*
X2164565Y40683826D02*
X2128851Y40612398D01*
X2093137Y40576683D01*
X2021708Y40540969D01*
X1807422Y40540969D01*
X1735994Y40576683D01*
X1700280Y40612398D01*
X1664565Y40683826D01*
X1664565Y40790969D01*
X1700280Y40862398D01*
X1735994Y40898112D01*
X1807422Y40933826D01*
X2021708Y40933826D01*
X2093137Y40898112D01*
X2128851Y40862398D01*
X2164565Y40790969D01*
X2164565Y40683826D01*
X1664565Y41255255D02*
X2164565Y41255255D01*
X1735994Y41255255D02*
X1700280Y41290969D01*
X1664565Y41362398D01*
X1664565Y41469540D01*
X1700280Y41540969D01*
X1771708Y41576683D01*
X2164565Y41576683D01*
X1664565Y41933826D02*
X2164565Y41933826D01*
X1735994Y41933826D02*
X1700280Y41969540D01*
X1664565Y42040969D01*
X1664565Y42148112D01*
X1700280Y42219540D01*
X1771708Y42255255D01*
X2164565Y42255255D01*
X2235994Y42433826D02*
X2235994Y43005255D01*
X1414565Y43326683D02*
X1414565Y43398112D01*
X1450280Y43469540D01*
X1485994Y43505255D01*
X1557422Y43540969D01*
X1700280Y43576683D01*
X1878851Y43576683D01*
X2021708Y43540969D01*
X2093137Y43505255D01*
X2128851Y43469540D01*
X2164565Y43398112D01*
X2164565Y43326683D01*
X2128851Y43255255D01*
X2093137Y43219540D01*
X2021708Y43183826D01*
X1878851Y43148112D01*
X1700280Y43148112D01*
X1557422Y43183826D01*
X1485994Y43219540D01*
X1450280Y43255255D01*
X1414565Y43326683D01*
X1485994Y43862398D02*
X1450280Y43898112D01*
X1414565Y43969540D01*
X1414565Y44148112D01*
X1450280Y44219540D01*
X1485994Y44255255D01*
X1557422Y44290969D01*
X1628851Y44290969D01*
X1735994Y44255255D01*
X2164565Y43826683D01*
X2164565Y44290969D01*
X2164565Y44540969D02*
X1664565Y44933826D01*
X1664565Y44540969D02*
X2164565Y44933826D01*
X1414565Y45362398D02*
X1414565Y45433826D01*
X1450280Y45505255D01*
X1485994Y45540969D01*
X1557422Y45576683D01*
X1700280Y45612398D01*
X1878851Y45612398D01*
X2021708Y45576683D01*
X2093137Y45540969D01*
X2128851Y45505255D01*
X2164565Y45433826D01*
X2164565Y45362398D01*
X2128851Y45290969D01*
X2093137Y45255255D01*
X2021708Y45219540D01*
X1878851Y45183826D01*
X1700280Y45183826D01*
X1557422Y45219540D01*
X1485994Y45255255D01*
X1450280Y45290969D01*
X1414565Y45362398D01*
X1414565Y45862398D02*
X1414565Y46326683D01*
X1700280Y46076683D01*
X1700280Y46183826D01*
X1735994Y46255255D01*
X1771708Y46290969D01*
X1843137Y46326683D01*
X2021708Y46326683D01*
X2093137Y46290969D01*
X2128851Y46255255D01*
X2164565Y46183826D01*
X2164565Y45969540D01*
X2128851Y45898112D01*
X2093137Y45862398D01*
X2235994Y46469540D02*
X2235994Y47040969D01*
X2164565Y47219540D02*
X1414565Y47219540D01*
X1414565Y47505255D01*
X1450280Y47576683D01*
X1485994Y47612398D01*
X1557422Y47648112D01*
X1664565Y47648112D01*
X1735994Y47612398D01*
X1771708Y47576683D01*
X1807422Y47505255D01*
X1807422Y47219540D01*
X2093137Y48398112D02*
X2128851Y48362398D01*
X2164565Y48255255D01*
X2164565Y48183826D01*
X2128851Y48076683D01*
X2057422Y48005255D01*
X1985994Y47969540D01*
X1843137Y47933826D01*
X1735994Y47933826D01*
X1593137Y47969540D01*
X1521708Y48005255D01*
X1450280Y48076683D01*
X1414565Y48183826D01*
X1414565Y48255255D01*
X1450280Y48362398D01*
X1485994Y48398112D01*
X2164565Y48719540D02*
X1414565Y48719540D01*
X2128851Y49362398D02*
X2164565Y49290969D01*
X2164565Y49148112D01*
X2128851Y49076683D01*
X2057422Y49040969D01*
X1771708Y49040969D01*
X1700280Y49076683D01*
X1664565Y49148112D01*
X1664565Y49290969D01*
X1700280Y49362398D01*
X1771708Y49398112D01*
X1843137Y49398112D01*
X1914565Y49040969D01*
G04 #@! TO.C,J5*
X2093137Y11422655D02*
X2128851Y11386940D01*
X2164565Y11279798D01*
X2164565Y11208369D01*
X2128851Y11101226D01*
X2057422Y11029798D01*
X1985994Y10994083D01*
X1843137Y10958369D01*
X1735994Y10958369D01*
X1593137Y10994083D01*
X1521708Y11029798D01*
X1450280Y11101226D01*
X1414565Y11208369D01*
X1414565Y11279798D01*
X1450280Y11386940D01*
X1485994Y11422655D01*
X2164565Y11851226D02*
X2128851Y11779798D01*
X2093137Y11744083D01*
X2021708Y11708369D01*
X1807422Y11708369D01*
X1735994Y11744083D01*
X1700280Y11779798D01*
X1664565Y11851226D01*
X1664565Y11958369D01*
X1700280Y12029798D01*
X1735994Y12065512D01*
X1807422Y12101226D01*
X2021708Y12101226D01*
X2093137Y12065512D01*
X2128851Y12029798D01*
X2164565Y11958369D01*
X2164565Y11851226D01*
X1664565Y12422655D02*
X2164565Y12422655D01*
X1735994Y12422655D02*
X1700280Y12458369D01*
X1664565Y12529798D01*
X1664565Y12636940D01*
X1700280Y12708369D01*
X1771708Y12744083D01*
X2164565Y12744083D01*
X1664565Y13101226D02*
X2164565Y13101226D01*
X1735994Y13101226D02*
X1700280Y13136940D01*
X1664565Y13208369D01*
X1664565Y13315512D01*
X1700280Y13386940D01*
X1771708Y13422655D01*
X2164565Y13422655D01*
X2235994Y13601226D02*
X2235994Y14172655D01*
X1414565Y14494083D02*
X1414565Y14565512D01*
X1450280Y14636940D01*
X1485994Y14672655D01*
X1557422Y14708369D01*
X1700280Y14744083D01*
X1878851Y14744083D01*
X2021708Y14708369D01*
X2093137Y14672655D01*
X2128851Y14636940D01*
X2164565Y14565512D01*
X2164565Y14494083D01*
X2128851Y14422655D01*
X2093137Y14386940D01*
X2021708Y14351226D01*
X1878851Y14315512D01*
X1700280Y14315512D01*
X1557422Y14351226D01*
X1485994Y14386940D01*
X1450280Y14422655D01*
X1414565Y14494083D01*
X1485994Y15029798D02*
X1450280Y15065512D01*
X1414565Y15136940D01*
X1414565Y15315512D01*
X1450280Y15386940D01*
X1485994Y15422655D01*
X1557422Y15458369D01*
X1628851Y15458369D01*
X1735994Y15422655D01*
X2164565Y14994083D01*
X2164565Y15458369D01*
X2164565Y15708369D02*
X1664565Y16101226D01*
X1664565Y15708369D02*
X2164565Y16101226D01*
X1414565Y16529798D02*
X1414565Y16601226D01*
X1450280Y16672655D01*
X1485994Y16708369D01*
X1557422Y16744083D01*
X1700280Y16779798D01*
X1878851Y16779798D01*
X2021708Y16744083D01*
X2093137Y16708369D01*
X2128851Y16672655D01*
X2164565Y16601226D01*
X2164565Y16529798D01*
X2128851Y16458369D01*
X2093137Y16422655D01*
X2021708Y16386940D01*
X1878851Y16351226D01*
X1700280Y16351226D01*
X1557422Y16386940D01*
X1485994Y16422655D01*
X1450280Y16458369D01*
X1414565Y16529798D01*
X1414565Y17029798D02*
X1414565Y17494083D01*
X1700280Y17244083D01*
X1700280Y17351226D01*
X1735994Y17422655D01*
X1771708Y17458369D01*
X1843137Y17494083D01*
X2021708Y17494083D01*
X2093137Y17458369D01*
X2128851Y17422655D01*
X2164565Y17351226D01*
X2164565Y17136940D01*
X2128851Y17065512D01*
X2093137Y17029798D01*
X2235994Y17636940D02*
X2235994Y18208369D01*
X2164565Y18386940D02*
X1414565Y18386940D01*
X1414565Y18672655D01*
X1450280Y18744083D01*
X1485994Y18779798D01*
X1557422Y18815512D01*
X1664565Y18815512D01*
X1735994Y18779798D01*
X1771708Y18744083D01*
X1807422Y18672655D01*
X1807422Y18386940D01*
X2093137Y19565512D02*
X2128851Y19529798D01*
X2164565Y19422655D01*
X2164565Y19351226D01*
X2128851Y19244083D01*
X2057422Y19172655D01*
X1985994Y19136940D01*
X1843137Y19101226D01*
X1735994Y19101226D01*
X1593137Y19136940D01*
X1521708Y19172655D01*
X1450280Y19244083D01*
X1414565Y19351226D01*
X1414565Y19422655D01*
X1450280Y19529798D01*
X1485994Y19565512D01*
X2164565Y19886940D02*
X1414565Y19886940D01*
X2128851Y20529798D02*
X2164565Y20458369D01*
X2164565Y20315512D01*
X2128851Y20244083D01*
X2057422Y20208369D01*
X1771708Y20208369D01*
X1700280Y20244083D01*
X1664565Y20315512D01*
X1664565Y20458369D01*
X1700280Y20529798D01*
X1771708Y20565512D01*
X1843137Y20565512D01*
X1914565Y20208369D01*
G04 #@! TO.C,J6*
X34445137Y11430455D02*
X34480851Y11394740D01*
X34516565Y11287598D01*
X34516565Y11216169D01*
X34480851Y11109026D01*
X34409422Y11037598D01*
X34337994Y11001883D01*
X34195137Y10966169D01*
X34087994Y10966169D01*
X33945137Y11001883D01*
X33873708Y11037598D01*
X33802280Y11109026D01*
X33766565Y11216169D01*
X33766565Y11287598D01*
X33802280Y11394740D01*
X33837994Y11430455D01*
X34516565Y11859026D02*
X34480851Y11787598D01*
X34445137Y11751883D01*
X34373708Y11716169D01*
X34159422Y11716169D01*
X34087994Y11751883D01*
X34052280Y11787598D01*
X34016565Y11859026D01*
X34016565Y11966169D01*
X34052280Y12037598D01*
X34087994Y12073312D01*
X34159422Y12109026D01*
X34373708Y12109026D01*
X34445137Y12073312D01*
X34480851Y12037598D01*
X34516565Y11966169D01*
X34516565Y11859026D01*
X34016565Y12430455D02*
X34516565Y12430455D01*
X34087994Y12430455D02*
X34052280Y12466169D01*
X34016565Y12537598D01*
X34016565Y12644740D01*
X34052280Y12716169D01*
X34123708Y12751883D01*
X34516565Y12751883D01*
X34016565Y13109026D02*
X34516565Y13109026D01*
X34087994Y13109026D02*
X34052280Y13144740D01*
X34016565Y13216169D01*
X34016565Y13323312D01*
X34052280Y13394740D01*
X34123708Y13430455D01*
X34516565Y13430455D01*
X34587994Y13609026D02*
X34587994Y14180455D01*
X33766565Y14501883D02*
X33766565Y14573312D01*
X33802280Y14644740D01*
X33837994Y14680455D01*
X33909422Y14716169D01*
X34052280Y14751883D01*
X34230851Y14751883D01*
X34373708Y14716169D01*
X34445137Y14680455D01*
X34480851Y14644740D01*
X34516565Y14573312D01*
X34516565Y14501883D01*
X34480851Y14430455D01*
X34445137Y14394740D01*
X34373708Y14359026D01*
X34230851Y14323312D01*
X34052280Y14323312D01*
X33909422Y14359026D01*
X33837994Y14394740D01*
X33802280Y14430455D01*
X33766565Y14501883D01*
X33837994Y15037598D02*
X33802280Y15073312D01*
X33766565Y15144740D01*
X33766565Y15323312D01*
X33802280Y15394740D01*
X33837994Y15430455D01*
X33909422Y15466169D01*
X33980851Y15466169D01*
X34087994Y15430455D01*
X34516565Y15001883D01*
X34516565Y15466169D01*
X34516565Y15716169D02*
X34016565Y16109026D01*
X34016565Y15716169D02*
X34516565Y16109026D01*
X33766565Y16537598D02*
X33766565Y16609026D01*
X33802280Y16680455D01*
X33837994Y16716169D01*
X33909422Y16751883D01*
X34052280Y16787598D01*
X34230851Y16787598D01*
X34373708Y16751883D01*
X34445137Y16716169D01*
X34480851Y16680455D01*
X34516565Y16609026D01*
X34516565Y16537598D01*
X34480851Y16466169D01*
X34445137Y16430455D01*
X34373708Y16394740D01*
X34230851Y16359026D01*
X34052280Y16359026D01*
X33909422Y16394740D01*
X33837994Y16430455D01*
X33802280Y16466169D01*
X33766565Y16537598D01*
X33766565Y17037598D02*
X33766565Y17501883D01*
X34052280Y17251883D01*
X34052280Y17359026D01*
X34087994Y17430455D01*
X34123708Y17466169D01*
X34195137Y17501883D01*
X34373708Y17501883D01*
X34445137Y17466169D01*
X34480851Y17430455D01*
X34516565Y17359026D01*
X34516565Y17144740D01*
X34480851Y17073312D01*
X34445137Y17037598D01*
X34587994Y17644740D02*
X34587994Y18216169D01*
X34516565Y18394740D02*
X33766565Y18394740D01*
X33766565Y18680455D01*
X33802280Y18751883D01*
X33837994Y18787598D01*
X33909422Y18823312D01*
X34016565Y18823312D01*
X34087994Y18787598D01*
X34123708Y18751883D01*
X34159422Y18680455D01*
X34159422Y18394740D01*
X34445137Y19573312D02*
X34480851Y19537598D01*
X34516565Y19430455D01*
X34516565Y19359026D01*
X34480851Y19251883D01*
X34409422Y19180455D01*
X34337994Y19144740D01*
X34195137Y19109026D01*
X34087994Y19109026D01*
X33945137Y19144740D01*
X33873708Y19180455D01*
X33802280Y19251883D01*
X33766565Y19359026D01*
X33766565Y19430455D01*
X33802280Y19537598D01*
X33837994Y19573312D01*
X34516565Y19894740D02*
X33766565Y19894740D01*
X34480851Y20537598D02*
X34516565Y20466169D01*
X34516565Y20323312D01*
X34480851Y20251883D01*
X34409422Y20216169D01*
X34123708Y20216169D01*
X34052280Y20251883D01*
X34016565Y20323312D01*
X34016565Y20466169D01*
X34052280Y20537598D01*
X34123708Y20573312D01*
X34195137Y20573312D01*
X34266565Y20216169D01*
G04 #@! TO.C,J1*
D11*
X14209322Y68754063D02*
X14256941Y68706444D01*
X14304560Y68563587D01*
X14304560Y68468349D01*
X14256941Y68325492D01*
X14161703Y68230254D01*
X14066465Y68182635D01*
X13875989Y68135016D01*
X13733132Y68135016D01*
X13542656Y68182635D01*
X13447418Y68230254D01*
X13352180Y68325492D01*
X13304560Y68468349D01*
X13304560Y68563587D01*
X13352180Y68706444D01*
X13399799Y68754063D01*
X14304560Y69325492D02*
X14256941Y69230254D01*
X14209322Y69182635D01*
X14114084Y69135016D01*
X13828370Y69135016D01*
X13733132Y69182635D01*
X13685513Y69230254D01*
X13637894Y69325492D01*
X13637894Y69468349D01*
X13685513Y69563587D01*
X13733132Y69611206D01*
X13828370Y69658825D01*
X14114084Y69658825D01*
X14209322Y69611206D01*
X14256941Y69563587D01*
X14304560Y69468349D01*
X14304560Y69325492D01*
X13637894Y70087397D02*
X14304560Y70087397D01*
X13733132Y70087397D02*
X13685513Y70135016D01*
X13637894Y70230254D01*
X13637894Y70373111D01*
X13685513Y70468349D01*
X13780751Y70515968D01*
X14304560Y70515968D01*
X13637894Y70992159D02*
X14304560Y70992159D01*
X13733132Y70992159D02*
X13685513Y71039778D01*
X13637894Y71135016D01*
X13637894Y71277873D01*
X13685513Y71373111D01*
X13780751Y71420730D01*
X14304560Y71420730D01*
X14399799Y71658825D02*
X14399799Y72420730D01*
X13304560Y72849301D02*
X13304560Y72944540D01*
X13352180Y73039778D01*
X13399799Y73087397D01*
X13495037Y73135016D01*
X13685513Y73182635D01*
X13923608Y73182635D01*
X14114084Y73135016D01*
X14209322Y73087397D01*
X14256941Y73039778D01*
X14304560Y72944540D01*
X14304560Y72849301D01*
X14256941Y72754063D01*
X14209322Y72706444D01*
X14114084Y72658825D01*
X13923608Y72611206D01*
X13685513Y72611206D01*
X13495037Y72658825D01*
X13399799Y72706444D01*
X13352180Y72754063D01*
X13304560Y72849301D01*
X13399799Y73563587D02*
X13352180Y73611206D01*
X13304560Y73706444D01*
X13304560Y73944540D01*
X13352180Y74039778D01*
X13399799Y74087397D01*
X13495037Y74135016D01*
X13590275Y74135016D01*
X13733132Y74087397D01*
X14304560Y73515968D01*
X14304560Y74135016D01*
X14304560Y74468349D02*
X13637894Y74992159D01*
X13637894Y74468349D02*
X14304560Y74992159D01*
X13304560Y75563587D02*
X13304560Y75658825D01*
X13352180Y75754063D01*
X13399799Y75801682D01*
X13495037Y75849301D01*
X13685513Y75896920D01*
X13923608Y75896920D01*
X14114084Y75849301D01*
X14209322Y75801682D01*
X14256941Y75754063D01*
X14304560Y75658825D01*
X14304560Y75563587D01*
X14256941Y75468349D01*
X14209322Y75420730D01*
X14114084Y75373111D01*
X13923608Y75325492D01*
X13685513Y75325492D01*
X13495037Y75373111D01*
X13399799Y75420730D01*
X13352180Y75468349D01*
X13304560Y75563587D01*
X13637894Y76754063D02*
X14304560Y76754063D01*
X13256941Y76515968D02*
X13971227Y76277873D01*
X13971227Y76896920D01*
X14399799Y77039778D02*
X14399799Y77801682D01*
X14209322Y78611206D02*
X14256941Y78563587D01*
X14304560Y78420730D01*
X14304560Y78325492D01*
X14256941Y78182635D01*
X14161703Y78087397D01*
X14066465Y78039778D01*
X13875989Y77992159D01*
X13733132Y77992159D01*
X13542656Y78039778D01*
X13447418Y78087397D01*
X13352180Y78182635D01*
X13304560Y78325492D01*
X13304560Y78420730D01*
X13352180Y78563587D01*
X13399799Y78611206D01*
X14304560Y79039778D02*
X13304560Y79039778D01*
X13304560Y79420730D01*
X13352180Y79515968D01*
X13399799Y79563587D01*
X13495037Y79611206D01*
X13637894Y79611206D01*
X13733132Y79563587D01*
X13780751Y79515968D01*
X13828370Y79420730D01*
X13828370Y79039778D01*
X13304560Y80039778D02*
X14114084Y80039778D01*
X14209322Y80087397D01*
X14256941Y80135016D01*
X14304560Y80230254D01*
X14304560Y80420730D01*
X14256941Y80515968D01*
X14209322Y80563587D01*
X14114084Y80611206D01*
X13304560Y80611206D01*
G04 #@! TO.C,J3*
X22507522Y65357103D02*
X22555141Y65309484D01*
X22602760Y65166627D01*
X22602760Y65071389D01*
X22555141Y64928532D01*
X22459903Y64833294D01*
X22364665Y64785675D01*
X22174189Y64738056D01*
X22031332Y64738056D01*
X21840856Y64785675D01*
X21745618Y64833294D01*
X21650380Y64928532D01*
X21602760Y65071389D01*
X21602760Y65166627D01*
X21650380Y65309484D01*
X21697999Y65357103D01*
X22602760Y65928532D02*
X22555141Y65833294D01*
X22507522Y65785675D01*
X22412284Y65738056D01*
X22126570Y65738056D01*
X22031332Y65785675D01*
X21983713Y65833294D01*
X21936094Y65928532D01*
X21936094Y66071389D01*
X21983713Y66166627D01*
X22031332Y66214246D01*
X22126570Y66261865D01*
X22412284Y66261865D01*
X22507522Y66214246D01*
X22555141Y66166627D01*
X22602760Y66071389D01*
X22602760Y65928532D01*
X21936094Y66690437D02*
X22602760Y66690437D01*
X22031332Y66690437D02*
X21983713Y66738056D01*
X21936094Y66833294D01*
X21936094Y66976151D01*
X21983713Y67071389D01*
X22078951Y67119008D01*
X22602760Y67119008D01*
X21936094Y67595199D02*
X22602760Y67595199D01*
X22031332Y67595199D02*
X21983713Y67642818D01*
X21936094Y67738056D01*
X21936094Y67880913D01*
X21983713Y67976151D01*
X22078951Y68023770D01*
X22602760Y68023770D01*
X22697999Y68261865D02*
X22697999Y69023770D01*
X21602760Y69452341D02*
X21602760Y69547580D01*
X21650380Y69642818D01*
X21697999Y69690437D01*
X21793237Y69738056D01*
X21983713Y69785675D01*
X22221808Y69785675D01*
X22412284Y69738056D01*
X22507522Y69690437D01*
X22555141Y69642818D01*
X22602760Y69547580D01*
X22602760Y69452341D01*
X22555141Y69357103D01*
X22507522Y69309484D01*
X22412284Y69261865D01*
X22221808Y69214246D01*
X21983713Y69214246D01*
X21793237Y69261865D01*
X21697999Y69309484D01*
X21650380Y69357103D01*
X21602760Y69452341D01*
X21697999Y70166627D02*
X21650380Y70214246D01*
X21602760Y70309484D01*
X21602760Y70547580D01*
X21650380Y70642818D01*
X21697999Y70690437D01*
X21793237Y70738056D01*
X21888475Y70738056D01*
X22031332Y70690437D01*
X22602760Y70119008D01*
X22602760Y70738056D01*
X22602760Y71071389D02*
X21936094Y71595199D01*
X21936094Y71071389D02*
X22602760Y71595199D01*
X21602760Y72166627D02*
X21602760Y72261865D01*
X21650380Y72357103D01*
X21697999Y72404722D01*
X21793237Y72452341D01*
X21983713Y72499960D01*
X22221808Y72499960D01*
X22412284Y72452341D01*
X22507522Y72404722D01*
X22555141Y72357103D01*
X22602760Y72261865D01*
X22602760Y72166627D01*
X22555141Y72071389D01*
X22507522Y72023770D01*
X22412284Y71976151D01*
X22221808Y71928532D01*
X21983713Y71928532D01*
X21793237Y71976151D01*
X21697999Y72023770D01*
X21650380Y72071389D01*
X21602760Y72166627D01*
X21936094Y73357103D02*
X22602760Y73357103D01*
X21555141Y73119008D02*
X22269427Y72880913D01*
X22269427Y73499960D01*
X22697999Y73642818D02*
X22697999Y74404722D01*
X22507522Y75214246D02*
X22555141Y75166627D01*
X22602760Y75023770D01*
X22602760Y74928532D01*
X22555141Y74785675D01*
X22459903Y74690437D01*
X22364665Y74642818D01*
X22174189Y74595199D01*
X22031332Y74595199D01*
X21840856Y74642818D01*
X21745618Y74690437D01*
X21650380Y74785675D01*
X21602760Y74928532D01*
X21602760Y75023770D01*
X21650380Y75166627D01*
X21697999Y75214246D01*
X22602760Y75642818D02*
X21602760Y75642818D01*
X21602760Y76023770D01*
X21650380Y76119008D01*
X21697999Y76166627D01*
X21793237Y76214246D01*
X21936094Y76214246D01*
X22031332Y76166627D01*
X22078951Y76119008D01*
X22126570Y76023770D01*
X22126570Y75642818D01*
X21602760Y76642818D02*
X22412284Y76642818D01*
X22507522Y76690437D01*
X22555141Y76738056D01*
X22602760Y76833294D01*
X22602760Y77023770D01*
X22555141Y77119008D01*
X22507522Y77166627D01*
X22412284Y77214246D01*
X21602760Y77214246D01*
G04 #@! TO.C,W1*
X136382232Y-3480131D02*
X136048899Y-3480131D01*
X136048899Y-4003940D02*
X136048899Y-3003940D01*
X136525089Y-3003940D01*
X136906041Y-4003940D02*
X136906041Y-3337274D01*
X136906041Y-3003940D02*
X136858422Y-3051560D01*
X136906041Y-3099179D01*
X136953660Y-3051560D01*
X136906041Y-3003940D01*
X136906041Y-3099179D01*
X137286994Y-4003940D02*
X137810803Y-3337274D01*
X137286994Y-3337274D02*
X137810803Y-4003940D01*
X138191756Y-4003940D02*
X138191756Y-3337274D01*
X138191756Y-3003940D02*
X138144137Y-3051560D01*
X138191756Y-3099179D01*
X138239375Y-3051560D01*
X138191756Y-3003940D01*
X138191756Y-3099179D01*
X138667946Y-3337274D02*
X138667946Y-4003940D01*
X138667946Y-3432512D02*
X138715565Y-3384893D01*
X138810803Y-3337274D01*
X138953660Y-3337274D01*
X139048899Y-3384893D01*
X139096518Y-3480131D01*
X139096518Y-4003940D01*
X140001280Y-3337274D02*
X140001280Y-4146798D01*
X139953660Y-4242036D01*
X139906041Y-4289655D01*
X139810803Y-4337274D01*
X139667946Y-4337274D01*
X139572708Y-4289655D01*
X140001280Y-3956321D02*
X139906041Y-4003940D01*
X139715565Y-4003940D01*
X139620327Y-3956321D01*
X139572708Y-3908702D01*
X139525089Y-3813464D01*
X139525089Y-3527750D01*
X139572708Y-3432512D01*
X139620327Y-3384893D01*
X139715565Y-3337274D01*
X139906041Y-3337274D01*
X140001280Y-3384893D01*
X141239375Y-4003940D02*
X141239375Y-3003940D01*
X141667946Y-4003940D02*
X141667946Y-3480131D01*
X141620327Y-3384893D01*
X141525089Y-3337274D01*
X141382232Y-3337274D01*
X141286994Y-3384893D01*
X141239375Y-3432512D01*
X142286994Y-4003940D02*
X142191756Y-3956321D01*
X142144137Y-3908702D01*
X142096518Y-3813464D01*
X142096518Y-3527750D01*
X142144137Y-3432512D01*
X142191756Y-3384893D01*
X142286994Y-3337274D01*
X142429851Y-3337274D01*
X142525089Y-3384893D01*
X142572708Y-3432512D01*
X142620327Y-3527750D01*
X142620327Y-3813464D01*
X142572708Y-3908702D01*
X142525089Y-3956321D01*
X142429851Y-4003940D01*
X142286994Y-4003940D01*
X143191756Y-4003940D02*
X143096518Y-3956321D01*
X143048899Y-3861083D01*
X143048899Y-3003940D01*
X143953660Y-3956321D02*
X143858422Y-4003940D01*
X143667946Y-4003940D01*
X143572708Y-3956321D01*
X143525089Y-3861083D01*
X143525089Y-3480131D01*
X143572708Y-3384893D01*
X143667946Y-3337274D01*
X143858422Y-3337274D01*
X143953660Y-3384893D01*
X144001280Y-3480131D01*
X144001280Y-3575369D01*
X143525089Y-3670607D01*
X139096518Y4096060D02*
X139334613Y3096060D01*
X139525089Y3810345D01*
X139715565Y3096060D01*
X139953660Y4096060D01*
X140858422Y3096060D02*
X140286994Y3096060D01*
X140572708Y3096060D02*
X140572708Y4096060D01*
X140477470Y3953202D01*
X140382232Y3857964D01*
X140286994Y3810345D01*
G04 #@! TO.C,W2*
X-3617768Y86519869D02*
X-3951101Y86519869D01*
X-3951101Y85996060D02*
X-3951101Y86996060D01*
X-3474911Y86996060D01*
X-3093959Y85996060D02*
X-3093959Y86662726D01*
X-3093959Y86996060D02*
X-3141578Y86948440D01*
X-3093959Y86900821D01*
X-3046340Y86948440D01*
X-3093959Y86996060D01*
X-3093959Y86900821D01*
X-2713006Y85996060D02*
X-2189197Y86662726D01*
X-2713006Y86662726D02*
X-2189197Y85996060D01*
X-1808244Y85996060D02*
X-1808244Y86662726D01*
X-1808244Y86996060D02*
X-1855863Y86948440D01*
X-1808244Y86900821D01*
X-1760625Y86948440D01*
X-1808244Y86996060D01*
X-1808244Y86900821D01*
X-1332054Y86662726D02*
X-1332054Y85996060D01*
X-1332054Y86567488D02*
X-1284435Y86615107D01*
X-1189197Y86662726D01*
X-1046340Y86662726D01*
X-951101Y86615107D01*
X-903482Y86519869D01*
X-903482Y85996060D01*
X1280Y86662726D02*
X1280Y85853202D01*
X-46340Y85757964D01*
X-93959Y85710345D01*
X-189197Y85662726D01*
X-332054Y85662726D01*
X-427292Y85710345D01*
X1280Y86043679D02*
X-93959Y85996060D01*
X-284435Y85996060D01*
X-379673Y86043679D01*
X-427292Y86091298D01*
X-474911Y86186536D01*
X-474911Y86472250D01*
X-427292Y86567488D01*
X-379673Y86615107D01*
X-284435Y86662726D01*
X-93959Y86662726D01*
X1280Y86615107D01*
X1239375Y85996060D02*
X1239375Y86996060D01*
X1667946Y85996060D02*
X1667946Y86519869D01*
X1620327Y86615107D01*
X1525089Y86662726D01*
X1382232Y86662726D01*
X1286994Y86615107D01*
X1239375Y86567488D01*
X2286994Y85996060D02*
X2191756Y86043679D01*
X2144137Y86091298D01*
X2096518Y86186536D01*
X2096518Y86472250D01*
X2144137Y86567488D01*
X2191756Y86615107D01*
X2286994Y86662726D01*
X2429851Y86662726D01*
X2525089Y86615107D01*
X2572708Y86567488D01*
X2620327Y86472250D01*
X2620327Y86186536D01*
X2572708Y86091298D01*
X2525089Y86043679D01*
X2429851Y85996060D01*
X2286994Y85996060D01*
X3191756Y85996060D02*
X3096518Y86043679D01*
X3048899Y86138917D01*
X3048899Y86996060D01*
X3953660Y86043679D02*
X3858422Y85996060D01*
X3667946Y85996060D01*
X3572708Y86043679D01*
X3525089Y86138917D01*
X3525089Y86519869D01*
X3572708Y86615107D01*
X3667946Y86662726D01*
X3858422Y86662726D01*
X3953660Y86615107D01*
X4001280Y86519869D01*
X4001280Y86424631D01*
X3525089Y86329393D01*
X-903482Y94096060D02*
X-665387Y93096060D01*
X-474911Y93810345D01*
X-284435Y93096060D01*
X-46340Y94096060D01*
X286994Y94000821D02*
X334613Y94048440D01*
X429851Y94096060D01*
X667946Y94096060D01*
X763184Y94048440D01*
X810803Y94000821D01*
X858422Y93905583D01*
X858422Y93810345D01*
X810803Y93667488D01*
X239375Y93096060D01*
X858422Y93096060D01*
G04 #@! TO.C,W3*
X136382232Y86519869D02*
X136048899Y86519869D01*
X136048899Y85996060D02*
X136048899Y86996060D01*
X136525089Y86996060D01*
X136906041Y85996060D02*
X136906041Y86662726D01*
X136906041Y86996060D02*
X136858422Y86948440D01*
X136906041Y86900821D01*
X136953660Y86948440D01*
X136906041Y86996060D01*
X136906041Y86900821D01*
X137286994Y85996060D02*
X137810803Y86662726D01*
X137286994Y86662726D02*
X137810803Y85996060D01*
X138191756Y85996060D02*
X138191756Y86662726D01*
X138191756Y86996060D02*
X138144137Y86948440D01*
X138191756Y86900821D01*
X138239375Y86948440D01*
X138191756Y86996060D01*
X138191756Y86900821D01*
X138667946Y86662726D02*
X138667946Y85996060D01*
X138667946Y86567488D02*
X138715565Y86615107D01*
X138810803Y86662726D01*
X138953660Y86662726D01*
X139048899Y86615107D01*
X139096518Y86519869D01*
X139096518Y85996060D01*
X140001280Y86662726D02*
X140001280Y85853202D01*
X139953660Y85757964D01*
X139906041Y85710345D01*
X139810803Y85662726D01*
X139667946Y85662726D01*
X139572708Y85710345D01*
X140001280Y86043679D02*
X139906041Y85996060D01*
X139715565Y85996060D01*
X139620327Y86043679D01*
X139572708Y86091298D01*
X139525089Y86186536D01*
X139525089Y86472250D01*
X139572708Y86567488D01*
X139620327Y86615107D01*
X139715565Y86662726D01*
X139906041Y86662726D01*
X140001280Y86615107D01*
X141239375Y85996060D02*
X141239375Y86996060D01*
X141667946Y85996060D02*
X141667946Y86519869D01*
X141620327Y86615107D01*
X141525089Y86662726D01*
X141382232Y86662726D01*
X141286994Y86615107D01*
X141239375Y86567488D01*
X142286994Y85996060D02*
X142191756Y86043679D01*
X142144137Y86091298D01*
X142096518Y86186536D01*
X142096518Y86472250D01*
X142144137Y86567488D01*
X142191756Y86615107D01*
X142286994Y86662726D01*
X142429851Y86662726D01*
X142525089Y86615107D01*
X142572708Y86567488D01*
X142620327Y86472250D01*
X142620327Y86186536D01*
X142572708Y86091298D01*
X142525089Y86043679D01*
X142429851Y85996060D01*
X142286994Y85996060D01*
X143191756Y85996060D02*
X143096518Y86043679D01*
X143048899Y86138917D01*
X143048899Y86996060D01*
X143953660Y86043679D02*
X143858422Y85996060D01*
X143667946Y85996060D01*
X143572708Y86043679D01*
X143525089Y86138917D01*
X143525089Y86519869D01*
X143572708Y86615107D01*
X143667946Y86662726D01*
X143858422Y86662726D01*
X143953660Y86615107D01*
X144001280Y86519869D01*
X144001280Y86424631D01*
X143525089Y86329393D01*
X139096518Y94096060D02*
X139334613Y93096060D01*
X139525089Y93810345D01*
X139715565Y93096060D01*
X139953660Y94096060D01*
X140239375Y94096060D02*
X140858422Y94096060D01*
X140525089Y93715107D01*
X140667946Y93715107D01*
X140763184Y93667488D01*
X140810803Y93619869D01*
X140858422Y93524631D01*
X140858422Y93286536D01*
X140810803Y93191298D01*
X140763184Y93143679D01*
X140667946Y93096060D01*
X140382232Y93096060D01*
X140286994Y93143679D01*
X140239375Y93191298D01*
G04 #@! TO.C,W4*
X-3617768Y-3480131D02*
X-3951101Y-3480131D01*
X-3951101Y-4003940D02*
X-3951101Y-3003940D01*
X-3474911Y-3003940D01*
X-3093959Y-4003940D02*
X-3093959Y-3337274D01*
X-3093959Y-3003940D02*
X-3141578Y-3051560D01*
X-3093959Y-3099179D01*
X-3046340Y-3051560D01*
X-3093959Y-3003940D01*
X-3093959Y-3099179D01*
X-2713006Y-4003940D02*
X-2189197Y-3337274D01*
X-2713006Y-3337274D02*
X-2189197Y-4003940D01*
X-1808244Y-4003940D02*
X-1808244Y-3337274D01*
X-1808244Y-3003940D02*
X-1855863Y-3051560D01*
X-1808244Y-3099179D01*
X-1760625Y-3051560D01*
X-1808244Y-3003940D01*
X-1808244Y-3099179D01*
X-1332054Y-3337274D02*
X-1332054Y-4003940D01*
X-1332054Y-3432512D02*
X-1284435Y-3384893D01*
X-1189197Y-3337274D01*
X-1046340Y-3337274D01*
X-951101Y-3384893D01*
X-903482Y-3480131D01*
X-903482Y-4003940D01*
X1280Y-3337274D02*
X1280Y-4146798D01*
X-46340Y-4242036D01*
X-93959Y-4289655D01*
X-189197Y-4337274D01*
X-332054Y-4337274D01*
X-427292Y-4289655D01*
X1280Y-3956321D02*
X-93959Y-4003940D01*
X-284435Y-4003940D01*
X-379673Y-3956321D01*
X-427292Y-3908702D01*
X-474911Y-3813464D01*
X-474911Y-3527750D01*
X-427292Y-3432512D01*
X-379673Y-3384893D01*
X-284435Y-3337274D01*
X-93959Y-3337274D01*
X1280Y-3384893D01*
X1239375Y-4003940D02*
X1239375Y-3003940D01*
X1667946Y-4003940D02*
X1667946Y-3480131D01*
X1620327Y-3384893D01*
X1525089Y-3337274D01*
X1382232Y-3337274D01*
X1286994Y-3384893D01*
X1239375Y-3432512D01*
X2286994Y-4003940D02*
X2191756Y-3956321D01*
X2144137Y-3908702D01*
X2096518Y-3813464D01*
X2096518Y-3527750D01*
X2144137Y-3432512D01*
X2191756Y-3384893D01*
X2286994Y-3337274D01*
X2429851Y-3337274D01*
X2525089Y-3384893D01*
X2572708Y-3432512D01*
X2620327Y-3527750D01*
X2620327Y-3813464D01*
X2572708Y-3908702D01*
X2525089Y-3956321D01*
X2429851Y-4003940D01*
X2286994Y-4003940D01*
X3191756Y-4003940D02*
X3096518Y-3956321D01*
X3048899Y-3861083D01*
X3048899Y-3003940D01*
X3953660Y-3956321D02*
X3858422Y-4003940D01*
X3667946Y-4003940D01*
X3572708Y-3956321D01*
X3525089Y-3861083D01*
X3525089Y-3480131D01*
X3572708Y-3384893D01*
X3667946Y-3337274D01*
X3858422Y-3337274D01*
X3953660Y-3384893D01*
X4001280Y-3480131D01*
X4001280Y-3575369D01*
X3525089Y-3670607D01*
X-903482Y4096060D02*
X-665387Y3096060D01*
X-474911Y3810345D01*
X-284435Y3096060D01*
X-46340Y4096060D01*
X763184Y3762726D02*
X763184Y3096060D01*
X525089Y4143679D02*
X286994Y3429393D01*
X906041Y3429393D01*
G04 #@! TO.C,W5*
X57111475Y69310098D02*
X57063856Y69262479D01*
X56920999Y69214860D01*
X56825760Y69214860D01*
X56682903Y69262479D01*
X56587665Y69357717D01*
X56540046Y69452955D01*
X56492427Y69643431D01*
X56492427Y69786288D01*
X56540046Y69976764D01*
X56587665Y70072002D01*
X56682903Y70167240D01*
X56825760Y70214860D01*
X56920999Y70214860D01*
X57063856Y70167240D01*
X57111475Y70119621D01*
X57968618Y69214860D02*
X57968618Y69738669D01*
X57920999Y69833907D01*
X57825760Y69881526D01*
X57635284Y69881526D01*
X57540046Y69833907D01*
X57968618Y69262479D02*
X57873380Y69214860D01*
X57635284Y69214860D01*
X57540046Y69262479D01*
X57492427Y69357717D01*
X57492427Y69452955D01*
X57540046Y69548193D01*
X57635284Y69595812D01*
X57873380Y69595812D01*
X57968618Y69643431D01*
X58444808Y69214860D02*
X58444808Y70214860D01*
X58444808Y69833907D02*
X58540046Y69881526D01*
X58730522Y69881526D01*
X58825760Y69833907D01*
X58873380Y69786288D01*
X58920999Y69691050D01*
X58920999Y69405336D01*
X58873380Y69310098D01*
X58825760Y69262479D01*
X58730522Y69214860D01*
X58540046Y69214860D01*
X58444808Y69262479D01*
X59492427Y69214860D02*
X59397189Y69262479D01*
X59349570Y69357717D01*
X59349570Y70214860D01*
X60254332Y69262479D02*
X60159094Y69214860D01*
X59968618Y69214860D01*
X59873380Y69262479D01*
X59825760Y69357717D01*
X59825760Y69738669D01*
X59873380Y69833907D01*
X59968618Y69881526D01*
X60159094Y69881526D01*
X60254332Y69833907D01*
X60301951Y69738669D01*
X60301951Y69643431D01*
X59825760Y69548193D01*
X61492427Y69214860D02*
X61492427Y70214860D01*
X61920999Y69214860D02*
X61920999Y69738669D01*
X61873380Y69833907D01*
X61778141Y69881526D01*
X61635284Y69881526D01*
X61540046Y69833907D01*
X61492427Y69786288D01*
X62540046Y69214860D02*
X62444808Y69262479D01*
X62397189Y69310098D01*
X62349570Y69405336D01*
X62349570Y69691050D01*
X62397189Y69786288D01*
X62444808Y69833907D01*
X62540046Y69881526D01*
X62682903Y69881526D01*
X62778141Y69833907D01*
X62825760Y69786288D01*
X62873380Y69691050D01*
X62873380Y69405336D01*
X62825760Y69310098D01*
X62778141Y69262479D01*
X62682903Y69214860D01*
X62540046Y69214860D01*
X63444808Y69214860D02*
X63349570Y69262479D01*
X63301951Y69357717D01*
X63301951Y70214860D01*
X64206713Y69262479D02*
X64111475Y69214860D01*
X63920999Y69214860D01*
X63825760Y69262479D01*
X63778141Y69357717D01*
X63778141Y69738669D01*
X63825760Y69833907D01*
X63920999Y69881526D01*
X64111475Y69881526D01*
X64206713Y69833907D01*
X64254332Y69738669D01*
X64254332Y69643431D01*
X63778141Y69548193D01*
G04 #@! TO.C,W6*
X57111475Y46810098D02*
X57063856Y46762479D01*
X56920999Y46714860D01*
X56825760Y46714860D01*
X56682903Y46762479D01*
X56587665Y46857717D01*
X56540046Y46952955D01*
X56492427Y47143431D01*
X56492427Y47286288D01*
X56540046Y47476764D01*
X56587665Y47572002D01*
X56682903Y47667240D01*
X56825760Y47714860D01*
X56920999Y47714860D01*
X57063856Y47667240D01*
X57111475Y47619621D01*
X57968618Y46714860D02*
X57968618Y47238669D01*
X57920999Y47333907D01*
X57825760Y47381526D01*
X57635284Y47381526D01*
X57540046Y47333907D01*
X57968618Y46762479D02*
X57873380Y46714860D01*
X57635284Y46714860D01*
X57540046Y46762479D01*
X57492427Y46857717D01*
X57492427Y46952955D01*
X57540046Y47048193D01*
X57635284Y47095812D01*
X57873380Y47095812D01*
X57968618Y47143431D01*
X58444808Y46714860D02*
X58444808Y47714860D01*
X58444808Y47333907D02*
X58540046Y47381526D01*
X58730522Y47381526D01*
X58825760Y47333907D01*
X58873380Y47286288D01*
X58920999Y47191050D01*
X58920999Y46905336D01*
X58873380Y46810098D01*
X58825760Y46762479D01*
X58730522Y46714860D01*
X58540046Y46714860D01*
X58444808Y46762479D01*
X59492427Y46714860D02*
X59397189Y46762479D01*
X59349570Y46857717D01*
X59349570Y47714860D01*
X60254332Y46762479D02*
X60159094Y46714860D01*
X59968618Y46714860D01*
X59873380Y46762479D01*
X59825760Y46857717D01*
X59825760Y47238669D01*
X59873380Y47333907D01*
X59968618Y47381526D01*
X60159094Y47381526D01*
X60254332Y47333907D01*
X60301951Y47238669D01*
X60301951Y47143431D01*
X59825760Y47048193D01*
X61492427Y46714860D02*
X61492427Y47714860D01*
X61920999Y46714860D02*
X61920999Y47238669D01*
X61873380Y47333907D01*
X61778141Y47381526D01*
X61635284Y47381526D01*
X61540046Y47333907D01*
X61492427Y47286288D01*
X62540046Y46714860D02*
X62444808Y46762479D01*
X62397189Y46810098D01*
X62349570Y46905336D01*
X62349570Y47191050D01*
X62397189Y47286288D01*
X62444808Y47333907D01*
X62540046Y47381526D01*
X62682903Y47381526D01*
X62778141Y47333907D01*
X62825760Y47286288D01*
X62873380Y47191050D01*
X62873380Y46905336D01*
X62825760Y46810098D01*
X62778141Y46762479D01*
X62682903Y46714860D01*
X62540046Y46714860D01*
X63444808Y46714860D02*
X63349570Y46762479D01*
X63301951Y46857717D01*
X63301951Y47714860D01*
X64206713Y46762479D02*
X64111475Y46714860D01*
X63920999Y46714860D01*
X63825760Y46762479D01*
X63778141Y46857717D01*
X63778141Y47238669D01*
X63825760Y47333907D01*
X63920999Y47381526D01*
X64111475Y47381526D01*
X64206713Y47333907D01*
X64254332Y47238669D01*
X64254332Y47143431D01*
X63778141Y47048193D01*
G04 #@! TO.C,W7*
X57111475Y24310098D02*
X57063856Y24262479D01*
X56920999Y24214860D01*
X56825760Y24214860D01*
X56682903Y24262479D01*
X56587665Y24357717D01*
X56540046Y24452955D01*
X56492427Y24643431D01*
X56492427Y24786288D01*
X56540046Y24976764D01*
X56587665Y25072002D01*
X56682903Y25167240D01*
X56825760Y25214860D01*
X56920999Y25214860D01*
X57063856Y25167240D01*
X57111475Y25119621D01*
X57968618Y24214860D02*
X57968618Y24738669D01*
X57920999Y24833907D01*
X57825760Y24881526D01*
X57635284Y24881526D01*
X57540046Y24833907D01*
X57968618Y24262479D02*
X57873380Y24214860D01*
X57635284Y24214860D01*
X57540046Y24262479D01*
X57492427Y24357717D01*
X57492427Y24452955D01*
X57540046Y24548193D01*
X57635284Y24595812D01*
X57873380Y24595812D01*
X57968618Y24643431D01*
X58444808Y24214860D02*
X58444808Y25214860D01*
X58444808Y24833907D02*
X58540046Y24881526D01*
X58730522Y24881526D01*
X58825760Y24833907D01*
X58873380Y24786288D01*
X58920999Y24691050D01*
X58920999Y24405336D01*
X58873380Y24310098D01*
X58825760Y24262479D01*
X58730522Y24214860D01*
X58540046Y24214860D01*
X58444808Y24262479D01*
X59492427Y24214860D02*
X59397189Y24262479D01*
X59349570Y24357717D01*
X59349570Y25214860D01*
X60254332Y24262479D02*
X60159094Y24214860D01*
X59968618Y24214860D01*
X59873380Y24262479D01*
X59825760Y24357717D01*
X59825760Y24738669D01*
X59873380Y24833907D01*
X59968618Y24881526D01*
X60159094Y24881526D01*
X60254332Y24833907D01*
X60301951Y24738669D01*
X60301951Y24643431D01*
X59825760Y24548193D01*
X61492427Y24214860D02*
X61492427Y25214860D01*
X61920999Y24214860D02*
X61920999Y24738669D01*
X61873380Y24833907D01*
X61778141Y24881526D01*
X61635284Y24881526D01*
X61540046Y24833907D01*
X61492427Y24786288D01*
X62540046Y24214860D02*
X62444808Y24262479D01*
X62397189Y24310098D01*
X62349570Y24405336D01*
X62349570Y24691050D01*
X62397189Y24786288D01*
X62444808Y24833907D01*
X62540046Y24881526D01*
X62682903Y24881526D01*
X62778141Y24833907D01*
X62825760Y24786288D01*
X62873380Y24691050D01*
X62873380Y24405336D01*
X62825760Y24310098D01*
X62778141Y24262479D01*
X62682903Y24214860D01*
X62540046Y24214860D01*
X63444808Y24214860D02*
X63349570Y24262479D01*
X63301951Y24357717D01*
X63301951Y25214860D01*
X64206713Y24262479D02*
X64111475Y24214860D01*
X63920999Y24214860D01*
X63825760Y24262479D01*
X63778141Y24357717D01*
X63778141Y24738669D01*
X63825760Y24833907D01*
X63920999Y24881526D01*
X64111475Y24881526D01*
X64206713Y24833907D01*
X64254332Y24738669D01*
X64254332Y24643431D01*
X63778141Y24548193D01*
G04 #@! TO.C,W8*
X57111475Y1810098D02*
X57063856Y1762479D01*
X56920999Y1714860D01*
X56825760Y1714860D01*
X56682903Y1762479D01*
X56587665Y1857717D01*
X56540046Y1952955D01*
X56492427Y2143431D01*
X56492427Y2286288D01*
X56540046Y2476764D01*
X56587665Y2572002D01*
X56682903Y2667240D01*
X56825760Y2714860D01*
X56920999Y2714860D01*
X57063856Y2667240D01*
X57111475Y2619621D01*
X57968618Y1714860D02*
X57968618Y2238669D01*
X57920999Y2333907D01*
X57825760Y2381526D01*
X57635284Y2381526D01*
X57540046Y2333907D01*
X57968618Y1762479D02*
X57873380Y1714860D01*
X57635284Y1714860D01*
X57540046Y1762479D01*
X57492427Y1857717D01*
X57492427Y1952955D01*
X57540046Y2048193D01*
X57635284Y2095812D01*
X57873380Y2095812D01*
X57968618Y2143431D01*
X58444808Y1714860D02*
X58444808Y2714860D01*
X58444808Y2333907D02*
X58540046Y2381526D01*
X58730522Y2381526D01*
X58825760Y2333907D01*
X58873380Y2286288D01*
X58920999Y2191050D01*
X58920999Y1905336D01*
X58873380Y1810098D01*
X58825760Y1762479D01*
X58730522Y1714860D01*
X58540046Y1714860D01*
X58444808Y1762479D01*
X59492427Y1714860D02*
X59397189Y1762479D01*
X59349570Y1857717D01*
X59349570Y2714860D01*
X60254332Y1762479D02*
X60159094Y1714860D01*
X59968618Y1714860D01*
X59873380Y1762479D01*
X59825760Y1857717D01*
X59825760Y2238669D01*
X59873380Y2333907D01*
X59968618Y2381526D01*
X60159094Y2381526D01*
X60254332Y2333907D01*
X60301951Y2238669D01*
X60301951Y2143431D01*
X59825760Y2048193D01*
X61492427Y1714860D02*
X61492427Y2714860D01*
X61920999Y1714860D02*
X61920999Y2238669D01*
X61873380Y2333907D01*
X61778141Y2381526D01*
X61635284Y2381526D01*
X61540046Y2333907D01*
X61492427Y2286288D01*
X62540046Y1714860D02*
X62444808Y1762479D01*
X62397189Y1810098D01*
X62349570Y1905336D01*
X62349570Y2191050D01*
X62397189Y2286288D01*
X62444808Y2333907D01*
X62540046Y2381526D01*
X62682903Y2381526D01*
X62778141Y2333907D01*
X62825760Y2286288D01*
X62873380Y2191050D01*
X62873380Y1905336D01*
X62825760Y1810098D01*
X62778141Y1762479D01*
X62682903Y1714860D01*
X62540046Y1714860D01*
X63444808Y1714860D02*
X63349570Y1762479D01*
X63301951Y1857717D01*
X63301951Y2714860D01*
X64206713Y1762479D02*
X64111475Y1714860D01*
X63920999Y1714860D01*
X63825760Y1762479D01*
X63778141Y1857717D01*
X63778141Y2238669D01*
X63825760Y2333907D01*
X63920999Y2381526D01*
X64111475Y2381526D01*
X64206713Y2333907D01*
X64254332Y2238669D01*
X64254332Y2143431D01*
X63778141Y2048193D01*
G04 #@! TO.C,W9*
X117111475Y72060098D02*
X117063856Y72012479D01*
X116920999Y71964860D01*
X116825760Y71964860D01*
X116682903Y72012479D01*
X116587665Y72107717D01*
X116540046Y72202955D01*
X116492427Y72393431D01*
X116492427Y72536288D01*
X116540046Y72726764D01*
X116587665Y72822002D01*
X116682903Y72917240D01*
X116825760Y72964860D01*
X116920999Y72964860D01*
X117063856Y72917240D01*
X117111475Y72869621D01*
X117968618Y71964860D02*
X117968618Y72488669D01*
X117920999Y72583907D01*
X117825760Y72631526D01*
X117635284Y72631526D01*
X117540046Y72583907D01*
X117968618Y72012479D02*
X117873380Y71964860D01*
X117635284Y71964860D01*
X117540046Y72012479D01*
X117492427Y72107717D01*
X117492427Y72202955D01*
X117540046Y72298193D01*
X117635284Y72345812D01*
X117873380Y72345812D01*
X117968618Y72393431D01*
X118444808Y71964860D02*
X118444808Y72964860D01*
X118444808Y72583907D02*
X118540046Y72631526D01*
X118730522Y72631526D01*
X118825760Y72583907D01*
X118873380Y72536288D01*
X118920999Y72441050D01*
X118920999Y72155336D01*
X118873380Y72060098D01*
X118825760Y72012479D01*
X118730522Y71964860D01*
X118540046Y71964860D01*
X118444808Y72012479D01*
X119492427Y71964860D02*
X119397189Y72012479D01*
X119349570Y72107717D01*
X119349570Y72964860D01*
X120254332Y72012479D02*
X120159094Y71964860D01*
X119968618Y71964860D01*
X119873380Y72012479D01*
X119825760Y72107717D01*
X119825760Y72488669D01*
X119873380Y72583907D01*
X119968618Y72631526D01*
X120159094Y72631526D01*
X120254332Y72583907D01*
X120301951Y72488669D01*
X120301951Y72393431D01*
X119825760Y72298193D01*
X121492427Y71964860D02*
X121492427Y72964860D01*
X121920999Y71964860D02*
X121920999Y72488669D01*
X121873380Y72583907D01*
X121778141Y72631526D01*
X121635284Y72631526D01*
X121540046Y72583907D01*
X121492427Y72536288D01*
X122540046Y71964860D02*
X122444808Y72012479D01*
X122397189Y72060098D01*
X122349570Y72155336D01*
X122349570Y72441050D01*
X122397189Y72536288D01*
X122444808Y72583907D01*
X122540046Y72631526D01*
X122682903Y72631526D01*
X122778141Y72583907D01*
X122825760Y72536288D01*
X122873380Y72441050D01*
X122873380Y72155336D01*
X122825760Y72060098D01*
X122778141Y72012479D01*
X122682903Y71964860D01*
X122540046Y71964860D01*
X123444808Y71964860D02*
X123349570Y72012479D01*
X123301951Y72107717D01*
X123301951Y72964860D01*
X124206713Y72012479D02*
X124111475Y71964860D01*
X123920999Y71964860D01*
X123825760Y72012479D01*
X123778141Y72107717D01*
X123778141Y72488669D01*
X123825760Y72583907D01*
X123920999Y72631526D01*
X124111475Y72631526D01*
X124206713Y72583907D01*
X124254332Y72488669D01*
X124254332Y72393431D01*
X123778141Y72298193D01*
G04 #@! TO.C,W10*
X117111475Y49560098D02*
X117063856Y49512479D01*
X116920999Y49464860D01*
X116825760Y49464860D01*
X116682903Y49512479D01*
X116587665Y49607717D01*
X116540046Y49702955D01*
X116492427Y49893431D01*
X116492427Y50036288D01*
X116540046Y50226764D01*
X116587665Y50322002D01*
X116682903Y50417240D01*
X116825760Y50464860D01*
X116920999Y50464860D01*
X117063856Y50417240D01*
X117111475Y50369621D01*
X117968618Y49464860D02*
X117968618Y49988669D01*
X117920999Y50083907D01*
X117825760Y50131526D01*
X117635284Y50131526D01*
X117540046Y50083907D01*
X117968618Y49512479D02*
X117873380Y49464860D01*
X117635284Y49464860D01*
X117540046Y49512479D01*
X117492427Y49607717D01*
X117492427Y49702955D01*
X117540046Y49798193D01*
X117635284Y49845812D01*
X117873380Y49845812D01*
X117968618Y49893431D01*
X118444808Y49464860D02*
X118444808Y50464860D01*
X118444808Y50083907D02*
X118540046Y50131526D01*
X118730522Y50131526D01*
X118825760Y50083907D01*
X118873380Y50036288D01*
X118920999Y49941050D01*
X118920999Y49655336D01*
X118873380Y49560098D01*
X118825760Y49512479D01*
X118730522Y49464860D01*
X118540046Y49464860D01*
X118444808Y49512479D01*
X119492427Y49464860D02*
X119397189Y49512479D01*
X119349570Y49607717D01*
X119349570Y50464860D01*
X120254332Y49512479D02*
X120159094Y49464860D01*
X119968618Y49464860D01*
X119873380Y49512479D01*
X119825760Y49607717D01*
X119825760Y49988669D01*
X119873380Y50083907D01*
X119968618Y50131526D01*
X120159094Y50131526D01*
X120254332Y50083907D01*
X120301951Y49988669D01*
X120301951Y49893431D01*
X119825760Y49798193D01*
X121492427Y49464860D02*
X121492427Y50464860D01*
X121920999Y49464860D02*
X121920999Y49988669D01*
X121873380Y50083907D01*
X121778141Y50131526D01*
X121635284Y50131526D01*
X121540046Y50083907D01*
X121492427Y50036288D01*
X122540046Y49464860D02*
X122444808Y49512479D01*
X122397189Y49560098D01*
X122349570Y49655336D01*
X122349570Y49941050D01*
X122397189Y50036288D01*
X122444808Y50083907D01*
X122540046Y50131526D01*
X122682903Y50131526D01*
X122778141Y50083907D01*
X122825760Y50036288D01*
X122873380Y49941050D01*
X122873380Y49655336D01*
X122825760Y49560098D01*
X122778141Y49512479D01*
X122682903Y49464860D01*
X122540046Y49464860D01*
X123444808Y49464860D02*
X123349570Y49512479D01*
X123301951Y49607717D01*
X123301951Y50464860D01*
X124206713Y49512479D02*
X124111475Y49464860D01*
X123920999Y49464860D01*
X123825760Y49512479D01*
X123778141Y49607717D01*
X123778141Y49988669D01*
X123825760Y50083907D01*
X123920999Y50131526D01*
X124111475Y50131526D01*
X124206713Y50083907D01*
X124254332Y49988669D01*
X124254332Y49893431D01*
X123778141Y49798193D01*
G04 #@! TO.C,W11*
X117111475Y4560098D02*
X117063856Y4512479D01*
X116920999Y4464860D01*
X116825760Y4464860D01*
X116682903Y4512479D01*
X116587665Y4607717D01*
X116540046Y4702955D01*
X116492427Y4893431D01*
X116492427Y5036288D01*
X116540046Y5226764D01*
X116587665Y5322002D01*
X116682903Y5417240D01*
X116825760Y5464860D01*
X116920999Y5464860D01*
X117063856Y5417240D01*
X117111475Y5369621D01*
X117968618Y4464860D02*
X117968618Y4988669D01*
X117920999Y5083907D01*
X117825760Y5131526D01*
X117635284Y5131526D01*
X117540046Y5083907D01*
X117968618Y4512479D02*
X117873380Y4464860D01*
X117635284Y4464860D01*
X117540046Y4512479D01*
X117492427Y4607717D01*
X117492427Y4702955D01*
X117540046Y4798193D01*
X117635284Y4845812D01*
X117873380Y4845812D01*
X117968618Y4893431D01*
X118444808Y4464860D02*
X118444808Y5464860D01*
X118444808Y5083907D02*
X118540046Y5131526D01*
X118730522Y5131526D01*
X118825760Y5083907D01*
X118873380Y5036288D01*
X118920999Y4941050D01*
X118920999Y4655336D01*
X118873380Y4560098D01*
X118825760Y4512479D01*
X118730522Y4464860D01*
X118540046Y4464860D01*
X118444808Y4512479D01*
X119492427Y4464860D02*
X119397189Y4512479D01*
X119349570Y4607717D01*
X119349570Y5464860D01*
X120254332Y4512479D02*
X120159094Y4464860D01*
X119968618Y4464860D01*
X119873380Y4512479D01*
X119825760Y4607717D01*
X119825760Y4988669D01*
X119873380Y5083907D01*
X119968618Y5131526D01*
X120159094Y5131526D01*
X120254332Y5083907D01*
X120301951Y4988669D01*
X120301951Y4893431D01*
X119825760Y4798193D01*
X121492427Y4464860D02*
X121492427Y5464860D01*
X121920999Y4464860D02*
X121920999Y4988669D01*
X121873380Y5083907D01*
X121778141Y5131526D01*
X121635284Y5131526D01*
X121540046Y5083907D01*
X121492427Y5036288D01*
X122540046Y4464860D02*
X122444808Y4512479D01*
X122397189Y4560098D01*
X122349570Y4655336D01*
X122349570Y4941050D01*
X122397189Y5036288D01*
X122444808Y5083907D01*
X122540046Y5131526D01*
X122682903Y5131526D01*
X122778141Y5083907D01*
X122825760Y5036288D01*
X122873380Y4941050D01*
X122873380Y4655336D01*
X122825760Y4560098D01*
X122778141Y4512479D01*
X122682903Y4464860D01*
X122540046Y4464860D01*
X123444808Y4464860D02*
X123349570Y4512479D01*
X123301951Y4607717D01*
X123301951Y5464860D01*
X124206713Y4512479D02*
X124111475Y4464860D01*
X123920999Y4464860D01*
X123825760Y4512479D01*
X123778141Y4607717D01*
X123778141Y4988669D01*
X123825760Y5083907D01*
X123920999Y5131526D01*
X124111475Y5131526D01*
X124206713Y5083907D01*
X124254332Y4988669D01*
X124254332Y4893431D01*
X123778141Y4798193D01*
G04 #@! TO.C,W12*
X117111475Y27060098D02*
X117063856Y27012479D01*
X116920999Y26964860D01*
X116825760Y26964860D01*
X116682903Y27012479D01*
X116587665Y27107717D01*
X116540046Y27202955D01*
X116492427Y27393431D01*
X116492427Y27536288D01*
X116540046Y27726764D01*
X116587665Y27822002D01*
X116682903Y27917240D01*
X116825760Y27964860D01*
X116920999Y27964860D01*
X117063856Y27917240D01*
X117111475Y27869621D01*
X117968618Y26964860D02*
X117968618Y27488669D01*
X117920999Y27583907D01*
X117825760Y27631526D01*
X117635284Y27631526D01*
X117540046Y27583907D01*
X117968618Y27012479D02*
X117873380Y26964860D01*
X117635284Y26964860D01*
X117540046Y27012479D01*
X117492427Y27107717D01*
X117492427Y27202955D01*
X117540046Y27298193D01*
X117635284Y27345812D01*
X117873380Y27345812D01*
X117968618Y27393431D01*
X118444808Y26964860D02*
X118444808Y27964860D01*
X118444808Y27583907D02*
X118540046Y27631526D01*
X118730522Y27631526D01*
X118825760Y27583907D01*
X118873380Y27536288D01*
X118920999Y27441050D01*
X118920999Y27155336D01*
X118873380Y27060098D01*
X118825760Y27012479D01*
X118730522Y26964860D01*
X118540046Y26964860D01*
X118444808Y27012479D01*
X119492427Y26964860D02*
X119397189Y27012479D01*
X119349570Y27107717D01*
X119349570Y27964860D01*
X120254332Y27012479D02*
X120159094Y26964860D01*
X119968618Y26964860D01*
X119873380Y27012479D01*
X119825760Y27107717D01*
X119825760Y27488669D01*
X119873380Y27583907D01*
X119968618Y27631526D01*
X120159094Y27631526D01*
X120254332Y27583907D01*
X120301951Y27488669D01*
X120301951Y27393431D01*
X119825760Y27298193D01*
X121492427Y26964860D02*
X121492427Y27964860D01*
X121920999Y26964860D02*
X121920999Y27488669D01*
X121873380Y27583907D01*
X121778141Y27631526D01*
X121635284Y27631526D01*
X121540046Y27583907D01*
X121492427Y27536288D01*
X122540046Y26964860D02*
X122444808Y27012479D01*
X122397189Y27060098D01*
X122349570Y27155336D01*
X122349570Y27441050D01*
X122397189Y27536288D01*
X122444808Y27583907D01*
X122540046Y27631526D01*
X122682903Y27631526D01*
X122778141Y27583907D01*
X122825760Y27536288D01*
X122873380Y27441050D01*
X122873380Y27155336D01*
X122825760Y27060098D01*
X122778141Y27012479D01*
X122682903Y26964860D01*
X122540046Y26964860D01*
X123444808Y26964860D02*
X123349570Y27012479D01*
X123301951Y27107717D01*
X123301951Y27964860D01*
X124206713Y27012479D02*
X124111475Y26964860D01*
X123920999Y26964860D01*
X123825760Y27012479D01*
X123778141Y27107717D01*
X123778141Y27488669D01*
X123825760Y27583907D01*
X123920999Y27631526D01*
X124111475Y27631526D01*
X124206713Y27583907D01*
X124254332Y27488669D01*
X124254332Y27393431D01*
X123778141Y27298193D01*
G04 #@! TD*
M02*
